# SCM (Grand Teton) — schematic netlist excerpt (pin names and nets, part order shuffled) for the footprints in the layout excerpt that follows; sources: Cadence DE-HDL packaged netlist, KiCad conversion of 12092022_DA0F0TMDCD0_F0T_Management_Board_D_brd_V3_OCP.brd

R197  Q_RES  1K 1% CHIP  pkg 0402LF  page 14 : A = P1V2_P1V0_I3C_VDDL1 ; B = I3C4_SPD_SDA
R519  Q_RES  0 5% CHIP  pkg 0402LF  page 34 : A = BMC_CPLD_GPIO_2 ; B = BMC_CPLD_GPIO_2_R2

(kicad_pcb
	(version 20260206)
	(generator "pcbnew")
	(generator_version "10.0")
	(general
		(thickness 1.6)
		(legacy_teardrops no)
	)
	(paper "A4")
	(title_block
		(title "12092022_DA0F0TMDCD0_F0T_Management_Board_D_brd_V3_OCP.brd")
		(comment 1 "Grand Teton / footprints 1117-1118 of 1440")
	)
	(layers
		(0 "F.Cu" signal "TOP")
		(4 "In1.Cu" signal "GND")
		(6 "In2.Cu" signal "IN1")
		(8 "In3.Cu" signal "GND1")
		(10 "In4.Cu" signal "IN2")
		(12 "In5.Cu" signal "VCC")
		(14 "In6.Cu" signal "VCC1")
		(16 "In7.Cu" signal "IN3")
		(18 "In8.Cu" signal "GND2")
		(20 "In9.Cu" signal "IN4")
		(22 "In10.Cu" signal "GND3")
		(2 "B.Cu" signal "BOTTOM")
		(9 "F.Adhes" user "F.Adhesive")
		(11 "B.Adhes" user "B.Adhesive")
		(13 "F.Paste" user "Package Geometry/Pastemask Top")
		(15 "B.Paste" user "Package Geometry/Pastemask Bottom")
		(5 "F.SilkS" user "Ref Des/Silkscreen Top")
		(7 "B.SilkS" user "Ref Des/Silkscreen Bottom")
		(1 "F.Mask" user "Board Geometry/Soldermask Top")
		(3 "B.Mask" user "Board Geometry/Soldermask Bottom")
		(17 "Dwgs.User" user "User.Drawings")
		(19 "Cmts.User" user "User.Comments")
		(21 "Eco1.User" user "User.Eco1")
		(23 "Eco2.User" user "User.Eco2")
		(25 "Edge.Cuts" user "Board Geometry/Outline")
		(27 "Margin" user)
		(31 "F.CrtYd" user "Package Geometry/Place Bound Top")
		(29 "B.CrtYd" user "Package Geometry/Place Bound Bottom")
		(35 "F.Fab" user "Ref Des/Assembly Top")
		(33 "B.Fab" user "Ref Des/Assembly Bottom")
	)
	(footprint ""
		(layer "B.Cu")
		(at 29.468826 -92.106242)
		(property "Reference" "R519"
			(at 0 0 0)
			(layer "B.SilkS")
			(hide yes)
			(effects
				(font
					(size 1.27 1.27)
				)
				(justify mirror)
			)
		)
		(property "Value" ""
			(at 0 0 0)
			(layer "B.Fab")
			(effects
				(font
					(size 1.27 1.27)
				)
				(justify mirror)
			)
		)
		(duplicate_pad_numbers_are_jumpers no)
		(fp_line
			(start -0.7874 -0.4064)
			(end -0.7874 0.4064)
			(stroke
				(width 0.1524)
				(type default)
			)
			(layer "B.SilkS")
		)
		(fp_line
			(start -0.7874 0.4064)
			(end 0.7874 0.4064)
			(stroke
				(width 0.1524)
				(type default)
			)
			(layer "B.SilkS")
		)
		(fp_line
			(start 0.7874 -0.4064)
			(end -0.7874 -0.4064)
			(stroke
				(width 0.1524)
				(type default)
			)
			(layer "B.SilkS")
		)
		(fp_line
			(start 0.7874 0.4064)
			(end 0.7874 -0.4064)
			(stroke
				(width 0.1524)
				(type default)
			)
			(layer "B.SilkS")
		)
		(fp_line
			(start -0.67945 -0.3048)
			(end -0.67945 0.3048)
			(stroke
				(width 0.1)
				(type default)
			)
			(layer "B.Fab")
		)
		(fp_line
			(start -0.67945 0.3048)
			(end -0.120396 0.3048)
			(stroke
				(width 0.1)
				(type default)
			)
			(layer "B.Fab")
		)
		(fp_line
			(start -0.12065 -0.3048)
			(end -0.67945 -0.3048)
			(stroke
				(width 0.1)
				(type default)
			)
			(layer "B.Fab")
		)
		(fp_line
			(start -0.12065 -0.2794)
			(end -0.12065 -0.3048)
			(stroke
				(width 0.1)
				(type default)
			)
			(layer "B.Fab")
		)
		(fp_line
			(start -0.120396 0.2794)
			(end 0.12065 0.2794)
			(stroke
				(width 0.1)
				(type default)
			)
			(layer "B.Fab")
		)
		(fp_line
			(start -0.120396 0.3048)
			(end -0.120396 0.2794)
			(stroke
				(width 0.1)
				(type default)
			)
			(layer "B.Fab")
		)
		(fp_line
			(start 0.12065 -0.305054)
			(end 0.12065 -0.2794)
			(stroke
				(width 0.1)
				(type default)
			)
			(layer "B.Fab")
		)
		(fp_line
			(start 0.12065 -0.2794)
			(end -0.12065 -0.2794)
			(stroke
				(width 0.1)
				(type default)
			)
			(layer "B.Fab")
		)
		(fp_line
			(start 0.12065 0.2794)
			(end 0.12065 0.3048)
			(stroke
				(width 0.1)
				(type default)
			)
			(layer "B.Fab")
		)
		(fp_line
			(start 0.12065 0.3048)
			(end 0.67945 0.3048)
			(stroke
				(width 0.1)
				(type default)
			)
			(layer "B.Fab")
		)
		(fp_line
			(start 0.67945 -0.305054)
			(end 0.12065 -0.305054)
			(stroke
				(width 0.1)
				(type default)
			)
			(layer "B.Fab")
		)
		(fp_line
			(start 0.67945 0.3048)
			(end 0.67945 -0.305054)
			(stroke
				(width 0.1)
				(type default)
			)
			(layer "B.Fab")
		)
		(pad "1" smd circle
			(at 0.40005 0 180)
			(size 0 0)
			(layers "B.Cu" "B.Mask" "B.Paste")
			(net "BMC_CPLD_GPIO_2")
		)
		(pad "2" smd circle
			(at -0.40005 0 180)
			(size 0 0)
			(layers "B.Cu" "B.Mask" "B.Paste")
			(net "BMC_CPLD_GPIO_2_R2")
		)
	)
	(footprint ""
		(layer "B.Cu")
		(at 41.913302 -63.756794 -90)
		(property "Reference" "R197"
			(at 0 0 90)
			(layer "B.SilkS")
			(hide yes)
			(effects
				(font
					(size 1.27 1.27)
				)
				(justify mirror)
			)
		)
		(property "Value" ""
			(at 0 0 90)
			(layer "B.Fab")
			(effects
				(font
					(size 1.27 1.27)
				)
				(justify mirror)
			)
		)
		(duplicate_pad_numbers_are_jumpers no)
		(fp_line
			(start -0.7874 0.4064)
			(end 0.7874 0.4064)
			(stroke
				(width 0.1524)
				(type default)
			)
			(layer "B.SilkS")
		)
		(fp_line
			(start 0.7874 0.4064)
			(end 0.7874 -0.4064)
			(stroke
				(width 0.1524)
				(type default)
			)
			(layer "B.SilkS")
		)
		(fp_line
			(start -0.7874 -0.4064)
			(end -0.7874 0.4064)
			(stroke
				(width 0.1524)
				(type default)
			)
			(layer "B.SilkS")
		)
		(fp_line
			(start 0.7874 -0.4064)
			(end -0.7874 -0.4064)
			(stroke
				(width 0.1524)
				(type default)
			)
			(layer "B.SilkS")
		)
		(fp_line
			(start -0.67945 0.3048)
			(end -0.120396 0.3048)
			(stroke
				(width 0.1)
				(type default)
			)
			(layer "B.Fab")
		)
		(fp_line
			(start -0.120396 0.3048)
			(end -0.120396 0.2794)
			(stroke
				(width 0.1)
				(type default)
			)
			(layer "B.Fab")
		)
		(fp_line
			(start 0.12065 0.3048)
			(end 0.67945 0.3048)
			(stroke
				(width 0.1)
				(type default)
			)
			(layer "B.Fab")
		)
		(fp_line
			(start 0.67945 0.3048)
			(end 0.67945 -0.305054)
			(stroke
				(width 0.1)
				(type default)
			)
			(layer "B.Fab")
		)
		(fp_line
			(start -0.120396 0.2794)
			(end 0.12065 0.2794)
			(stroke
				(width 0.1)
				(type default)
			)
			(layer "B.Fab")
		)
		(fp_line
			(start 0.12065 0.2794)
			(end 0.12065 0.3048)
			(stroke
				(width 0.1)
				(type default)
			)
			(layer "B.Fab")
		)
		(fp_line
			(start -0.12065 -0.2794)
			(end -0.12065 -0.3048)
			(stroke
				(width 0.1)
				(type default)
			)
			(layer "B.Fab")
		)
		(fp_line
			(start 0.12065 -0.2794)
			(end -0.12065 -0.2794)
			(stroke
				(width 0.1)
				(type default)
			)
			(layer "B.Fab")
		)
		(fp_line
			(start -0.67945 -0.3048)
			(end -0.67945 0.3048)
			(stroke
				(width 0.1)
				(type default)
			)
			(layer "B.Fab")
		)
		(fp_line
			(start -0.12065 -0.3048)
			(end -0.67945 -0.3048)
			(stroke
				(width 0.1)
				(type default)
			)
			(layer "B.Fab")
		)
		(fp_line
			(start 0.12065 -0.305054)
			(end 0.12065 -0.2794)
			(stroke
				(width 0.1)
				(type default)
			)
			(layer "B.Fab")
		)
		(fp_line
			(start 0.67945 -0.305054)
			(end 0.12065 -0.305054)
			(stroke
				(width 0.1)
				(type default)
			)
			(layer "B.Fab")
		)
		(pad "1" smd circle
			(at 0.40005 0 90)
			(size 0 0)
			(layers "B.Cu" "B.Mask" "B.Paste")
			(net "P1V2_P1V0_I3C_VDDL1")
		)
		(pad "2" smd circle
			(at -0.40005 0 90)
			(size 0 0)
			(layers "B.Cu" "B.Mask" "B.Paste")
			(net "I3C4_SPD_SDA")
		)
	)
)
